(kicad_pcb
	(version 20260206)
	(generator "pcbnew")
	(generator_version "10.0")
	(general
		(thickness 1.6)
		(legacy_teardrops no)
	)
	(paper "A4")
	(title_block
		(title "04192023_DAF0TMB3IC0_F0TG_MB_C_brd_V02_OCP.brd")
		(comment 1 "Grand Teton / footprints 5002-5007 of 8354")
	)
	(layers
		(0 "F.Cu" signal "TOP")
		(4 "In1.Cu" signal "GND")
		(6 "In2.Cu" signal "IN1")
		(8 "In3.Cu" signal "GND1")
		(10 "In4.Cu" signal "IN2")
		(12 "In5.Cu" signal "GND2")
		(14 "In6.Cu" signal "IN3")
		(16 "In7.Cu" signal "GND3")
		(18 "In8.Cu" signal "VCC")
		(20 "In9.Cu" signal "VCC1")
		(22 "In10.Cu" signal "GND4")
		(24 "In11.Cu" signal "IN4")
		(26 "In12.Cu" signal "GND5")
		(28 "In13.Cu" signal "IN5")
		(30 "In14.Cu" signal "GND6")
		(32 "In15.Cu" signal "IN6")
		(34 "In16.Cu" signal "GND7")
		(2 "B.Cu" signal "BOTTOM")
		(9 "F.Adhes" user "F.Adhesive")
		(11 "B.Adhes" user "B.Adhesive")
		(13 "F.Paste" user "Package Geometry/Pastemask Top")
		(15 "B.Paste" user "Package Geometry/Pastemask Bottom")
		(5 "F.SilkS" user "Ref Des/Silkscreen Top")
		(7 "B.SilkS" user "Ref Des/Silkscreen Bottom")
		(1 "F.Mask" user "Board Geometry/Soldermask Top")
		(3 "B.Mask" user "Board Geometry/Soldermask Bottom")
		(17 "Dwgs.User" user "User.Drawings")
		(19 "Cmts.User" user "User.Comments")
		(21 "Eco1.User" user "User.Eco1")
		(23 "Eco2.User" user "User.Eco2")
		(25 "Edge.Cuts" user "Board Geometry/Outline")
		(27 "Margin" user)
		(31 "F.CrtYd" user "Package Geometry/Place Bound Top")
		(29 "B.CrtYd" user "Package Geometry/Place Bound Bottom")
		(35 "F.Fab" user "Ref Des/Assembly Top")
		(33 "B.Fab" user "Ref Des/Assembly Bottom")
	)
	(footprint ""
		(layer "B.Cu")
		(at 189.865 -100.294948 90)
		(property "Reference" "R221"
			(at 0 0 90)
			(layer "B.SilkS")
			(hide yes)
			(effects
				(font
					(size 1.27 1.27)
				)
				(justify mirror)
			)
		)
		(property "Value" ""
			(at 0 0 90)
			(layer "B.Fab")
			(effects
				(font
					(size 1.27 1.27)
				)
				(justify mirror)
			)
		)
		(duplicate_pad_numbers_are_jumpers no)
		(fp_line
			(start 0.7874 -0.4064)
			(end -0.7874 -0.4064)
			(stroke
				(width 0.1524)
				(type default)
			)
			(layer "B.SilkS")
		)
		(fp_line
			(start -0.7874 -0.4064)
			(end -0.7874 0.4064)
			(stroke
				(width 0.1524)
				(type default)
			)
			(layer "B.SilkS")
		)
		(fp_line
			(start 0.7874 0.4064)
			(end 0.7874 -0.4064)
			(stroke
				(width 0.1524)
				(type default)
			)
			(layer "B.SilkS")
		)
		(fp_line
			(start -0.7874 0.4064)
			(end 0.7874 0.4064)
			(stroke
				(width 0.1524)
				(type default)
			)
			(layer "B.SilkS")
		)
		(fp_line
			(start 0.67945 -0.305054)
			(end 0.12065 -0.305054)
			(stroke
				(width 0.1)
				(type default)
			)
			(layer "B.Fab")
		)
		(fp_line
			(start 0.12065 -0.305054)
			(end 0.12065 -0.2794)
			(stroke
				(width 0.1)
				(type default)
			)
			(layer "B.Fab")
		)
		(fp_line
			(start -0.12065 -0.3048)
			(end -0.67945 -0.3048)
			(stroke
				(width 0.1)
				(type default)
			)
			(layer "B.Fab")
		)
		(fp_line
			(start -0.67945 -0.3048)
			(end -0.67945 0.3048)
			(stroke
				(width 0.1)
				(type default)
			)
			(layer "B.Fab")
		)
		(fp_line
			(start 0.12065 -0.2794)
			(end -0.12065 -0.2794)
			(stroke
				(width 0.1)
				(type default)
			)
			(layer "B.Fab")
		)
		(fp_line
			(start -0.12065 -0.2794)
			(end -0.12065 -0.3048)
			(stroke
				(width 0.1)
				(type default)
			)
			(layer "B.Fab")
		)
		(fp_line
			(start 0.12065 0.2794)
			(end 0.12065 0.3048)
			(stroke
				(width 0.1)
				(type default)
			)
			(layer "B.Fab")
		)
		(fp_line
			(start -0.120396 0.2794)
			(end 0.12065 0.2794)
			(stroke
				(width 0.1)
				(type default)
			)
			(layer "B.Fab")
		)
		(fp_line
			(start 0.67945 0.3048)
			(end 0.67945 -0.305054)
			(stroke
				(width 0.1)
				(type default)
			)
			(layer "B.Fab")
		)
		(fp_line
			(start 0.12065 0.3048)
			(end 0.67945 0.3048)
			(stroke
				(width 0.1)
				(type default)
			)
			(layer "B.Fab")
		)
		(fp_line
			(start -0.120396 0.3048)
			(end -0.120396 0.2794)
			(stroke
				(width 0.1)
				(type default)
			)
			(layer "B.Fab")
		)
		(fp_line
			(start -0.67945 0.3048)
			(end -0.120396 0.3048)
			(stroke
				(width 0.1)
				(type default)
			)
			(layer "B.Fab")
		)
		(pad "1" smd circle
			(at 0.40005 0 270)
			(size 0 0)
			(layers "B.Cu" "B.Mask" "B.Paste")
			(net "FM_CPU0_SA1")
		)
		(pad "2" smd circle
			(at -0.40005 0 270)
			(size 0 0)
			(layers "B.Cu" "B.Mask" "B.Paste")
			(net "CPU0_SA1")
		)
	)
	(footprint ""
		(layer "B.Cu")
		(at 136.459468 -41.028112 90)
		(property "Reference" "C6030"
			(at 0 0 90)
			(layer "B.SilkS")
			(hide yes)
			(effects
				(font
					(size 1.27 1.27)
				)
				(justify mirror)
			)
		)
		(property "Value" ""
			(at 0 0 90)
			(layer "B.Fab")
			(effects
				(font
					(size 1.27 1.27)
				)
				(justify mirror)
			)
		)
		(duplicate_pad_numbers_are_jumpers no)
		(fp_line
			(start 1.2954 -0.5842)
			(end -1.2954 -0.5842)
			(stroke
				(width 0.1524)
				(type default)
			)
			(layer "B.SilkS")
		)
		(fp_line
			(start -1.2954 -0.5842)
			(end -1.2954 0.5842)
			(stroke
				(width 0.1524)
				(type default)
			)
			(layer "B.SilkS")
		)
		(fp_line
			(start 1.2954 0.5842)
			(end 1.2954 -0.5842)
			(stroke
				(width 0.1524)
				(type default)
			)
			(layer "B.SilkS")
		)
		(fp_line
			(start -1.2954 0.5842)
			(end 1.2954 0.5842)
			(stroke
				(width 0.1524)
				(type default)
			)
			(layer "B.SilkS")
		)
		(fp_line
			(start 0.8636 -0.4572)
			(end -0.8636 -0.4572)
			(stroke
				(width 0.1)
				(type default)
			)
			(layer "B.Fab")
		)
		(fp_line
			(start -0.8636 -0.4572)
			(end -0.8636 -0.4064)
			(stroke
				(width 0.1)
				(type default)
			)
			(layer "B.Fab")
		)
		(fp_line
			(start 1.1938 -0.4064)
			(end 0.8636 -0.4064)
			(stroke
				(width 0.1)
				(type default)
			)
			(layer "B.Fab")
		)
		(fp_line
			(start 0.8636 -0.4064)
			(end 0.8636 -0.4572)
			(stroke
				(width 0.1)
				(type default)
			)
			(layer "B.Fab")
		)
		(fp_line
			(start -0.8636 -0.4064)
			(end -1.1938 -0.4064)
			(stroke
				(width 0.1)
				(type default)
			)
			(layer "B.Fab")
		)
		(fp_line
			(start -1.1938 -0.4064)
			(end -1.1938 0.4064)
			(stroke
				(width 0.1)
				(type default)
			)
			(layer "B.Fab")
		)
		(fp_line
			(start 1.1938 0.4064)
			(end 1.1938 -0.4064)
			(stroke
				(width 0.1)
				(type default)
			)
			(layer "B.Fab")
		)
		(fp_line
			(start 0.8636 0.4064)
			(end 1.1938 0.4064)
			(stroke
				(width 0.1)
				(type default)
			)
			(layer "B.Fab")
		)
		(fp_line
			(start -0.8636 0.4064)
			(end -0.8636 0.4572)
			(stroke
				(width 0.1)
				(type default)
			)
			(layer "B.Fab")
		)
		(fp_line
			(start -1.1938 0.4064)
			(end -0.8636 0.4064)
			(stroke
				(width 0.1)
				(type default)
			)
			(layer "B.Fab")
		)
		(fp_line
			(start 0.8636 0.4572)
			(end 0.8636 0.4064)
			(stroke
				(width 0.1)
				(type default)
			)
			(layer "B.Fab")
		)
		(fp_line
			(start -0.8636 0.4572)
			(end 0.8636 0.4572)
			(stroke
				(width 0.1)
				(type default)
			)
			(layer "B.Fab")
		)
		(pad "1" smd rect
			(at 0.7366 0)
			(size 0.7112 0.8128)
			(layers "B.Cu" "B.Mask" "B.Paste")
			(net "P1V2_CPU0_USB_DVDD12")
		)
		(pad "2" smd rect
			(at -0.7366 0)
			(size 0.7112 0.8128)
			(layers "B.Cu" "B.Mask" "B.Paste")
			(net "GND")
		)
	)
	(footprint ""
		(layer "B.Cu")
		(at 172.72762 -194.885564 180)
		(property "Reference" "R774"
			(at 0 0 0)
			(layer "B.SilkS")
			(hide yes)
			(effects
				(font
					(size 1.27 1.27)
				)
				(justify mirror)
			)
		)
		(property "Value" ""
			(at 0 0 0)
			(layer "B.Fab")
			(effects
				(font
					(size 1.27 1.27)
				)
				(justify mirror)
			)
		)
		(duplicate_pad_numbers_are_jumpers no)
		(fp_line
			(start 0.7874 0.4064)
			(end 0.7874 -0.4064)
			(stroke
				(width 0.1524)
				(type default)
			)
			(layer "B.SilkS")
		)
		(fp_line
			(start 0.7874 -0.4064)
			(end -0.7874 -0.4064)
			(stroke
				(width 0.1524)
				(type default)
			)
			(layer "B.SilkS")
		)
		(fp_line
			(start -0.7874 0.4064)
			(end 0.7874 0.4064)
			(stroke
				(width 0.1524)
				(type default)
			)
			(layer "B.SilkS")
		)
		(fp_line
			(start -0.7874 -0.4064)
			(end -0.7874 0.4064)
			(stroke
				(width 0.1524)
				(type default)
			)
			(layer "B.SilkS")
		)
		(fp_line
			(start 0.67945 0.3048)
			(end 0.67945 -0.305054)
			(stroke
				(width 0.1)
				(type default)
			)
			(layer "B.Fab")
		)
		(fp_line
			(start 0.67945 -0.305054)
			(end 0.12065 -0.305054)
			(stroke
				(width 0.1)
				(type default)
			)
			(layer "B.Fab")
		)
		(fp_line
			(start 0.12065 0.3048)
			(end 0.67945 0.3048)
			(stroke
				(width 0.1)
				(type default)
			)
			(layer "B.Fab")
		)
		(fp_line
			(start 0.12065 0.2794)
			(end 0.12065 0.3048)
			(stroke
				(width 0.1)
				(type default)
			)
			(layer "B.Fab")
		)
		(fp_line
			(start 0.12065 -0.2794)
			(end -0.12065 -0.2794)
			(stroke
				(width 0.1)
				(type default)
			)
			(layer "B.Fab")
		)
		(fp_line
			(start 0.12065 -0.305054)
			(end 0.12065 -0.2794)
			(stroke
				(width 0.1)
				(type default)
			)
			(layer "B.Fab")
		)
		(fp_line
			(start -0.120396 0.3048)
			(end -0.120396 0.2794)
			(stroke
				(width 0.1)
				(type default)
			)
			(layer "B.Fab")
		)
		(fp_line
			(start -0.120396 0.2794)
			(end 0.12065 0.2794)
			(stroke
				(width 0.1)
				(type default)
			)
			(layer "B.Fab")
		)
		(fp_line
			(start -0.12065 -0.2794)
			(end -0.12065 -0.3048)
			(stroke
				(width 0.1)
				(type default)
			)
			(layer "B.Fab")
		)
		(fp_line
			(start -0.12065 -0.3048)
			(end -0.67945 -0.3048)
			(stroke
				(width 0.1)
				(type default)
			)
			(layer "B.Fab")
		)
		(fp_line
			(start -0.67945 0.3048)
			(end -0.120396 0.3048)
			(stroke
				(width 0.1)
				(type default)
			)
			(layer "B.Fab")
		)
		(fp_line
			(start -0.67945 -0.3048)
			(end -0.67945 0.3048)
			(stroke
				(width 0.1)
				(type default)
			)
			(layer "B.Fab")
		)
		(pad "1" smd circle
			(at 0.40005 0)
			(size 0 0)
			(layers "B.Cu" "B.Mask" "B.Paste")
			(net "PD_CHH_CPU1_DIMM_SAA")
		)
		(pad "2" smd circle
			(at -0.40005 0)
			(size 0 0)
			(layers "B.Cu" "B.Mask" "B.Paste")
			(net "GND")
		)
	)
	(footprint ""
		(layer "B.Cu")
		(at 307.34127 -194.98691 180)
		(property "Reference" "R1568"
			(at 0 0 0)
			(layer "B.SilkS")
			(hide yes)
			(effects
				(font
					(size 1.27 1.27)
				)
				(justify mirror)
			)
		)
		(property "Value" ""
			(at 0 0 0)
			(layer "B.Fab")
			(effects
				(font
					(size 1.27 1.27)
				)
				(justify mirror)
			)
		)
		(duplicate_pad_numbers_are_jumpers no)
		(fp_line
			(start 0.7874 0.4064)
			(end 0.7874 -0.4064)
			(stroke
				(width 0.1524)
				(type default)
			)
			(layer "B.SilkS")
		)
		(fp_line
			(start 0.7874 -0.4064)
			(end -0.7874 -0.4064)
			(stroke
				(width 0.1524)
				(type default)
			)
			(layer "B.SilkS")
		)
		(fp_line
			(start -0.7874 0.4064)
			(end 0.7874 0.4064)
			(stroke
				(width 0.1524)
				(type default)
			)
			(layer "B.SilkS")
		)
		(fp_line
			(start -0.7874 -0.4064)
			(end -0.7874 0.4064)
			(stroke
				(width 0.1524)
				(type default)
			)
			(layer "B.SilkS")
		)
		(fp_line
			(start 0.67945 0.3048)
			(end 0.67945 -0.305054)
			(stroke
				(width 0.1)
				(type default)
			)
			(layer "B.Fab")
		)
		(fp_line
			(start 0.67945 -0.305054)
			(end 0.12065 -0.305054)
			(stroke
				(width 0.1)
				(type default)
			)
			(layer "B.Fab")
		)
		(fp_line
			(start 0.12065 0.3048)
			(end 0.67945 0.3048)
			(stroke
				(width 0.1)
				(type default)
			)
			(layer "B.Fab")
		)
		(fp_line
			(start 0.12065 0.2794)
			(end 0.12065 0.3048)
			(stroke
				(width 0.1)
				(type default)
			)
			(layer "B.Fab")
		)
		(fp_line
			(start 0.12065 -0.2794)
			(end -0.12065 -0.2794)
			(stroke
				(width 0.1)
				(type default)
			)
			(layer "B.Fab")
		)
		(fp_line
			(start 0.12065 -0.305054)
			(end 0.12065 -0.2794)
			(stroke
				(width 0.1)
				(type default)
			)
			(layer "B.Fab")
		)
		(fp_line
			(start -0.120396 0.3048)
			(end -0.120396 0.2794)
			(stroke
				(width 0.1)
				(type default)
			)
			(layer "B.Fab")
		)
		(fp_line
			(start -0.120396 0.2794)
			(end 0.12065 0.2794)
			(stroke
				(width 0.1)
				(type default)
			)
			(layer "B.Fab")
		)
		(fp_line
			(start -0.12065 -0.2794)
			(end -0.12065 -0.3048)
			(stroke
				(width 0.1)
				(type default)
			)
			(layer "B.Fab")
		)
		(fp_line
			(start -0.12065 -0.3048)
			(end -0.67945 -0.3048)
			(stroke
				(width 0.1)
				(type default)
			)
			(layer "B.Fab")
		)
		(fp_line
			(start -0.67945 0.3048)
			(end -0.120396 0.3048)
			(stroke
				(width 0.1)
				(type default)
			)
			(layer "B.Fab")
		)
		(fp_line
			(start -0.67945 -0.3048)
			(end -0.67945 0.3048)
			(stroke
				(width 0.1)
				(type default)
			)
			(layer "B.Fab")
		)
		(pad "1" smd circle
			(at 0.40005 0)
			(size 0 0)
			(layers "B.Cu" "B.Mask" "B.Paste")
			(net "I3C_SPD_DDRAF_CPU0_SCL")
		)
		(pad "2" smd circle
			(at -0.40005 0)
			(size 0 0)
			(layers "B.Cu" "B.Mask" "B.Paste")
			(net "I3C_SPD_DDRA_CPU0_SCL")
		)
	)
	(footprint ""
		(layer "B.Cu")
		(at 453.432418 -195.92671 180)
		(property "Reference" "R1686"
			(at 0 0 0)
			(layer "B.SilkS")
			(hide yes)
			(effects
				(font
					(size 1.27 1.27)
				)
				(justify mirror)
			)
		)
		(property "Value" ""
			(at 0 0 0)
			(layer "B.Fab")
			(effects
				(font
					(size 1.27 1.27)
				)
				(justify mirror)
			)
		)
		(duplicate_pad_numbers_are_jumpers no)
		(fp_line
			(start 0.7874 0.4064)
			(end 0.7874 -0.4064)
			(stroke
				(width 0.1524)
				(type default)
			)
			(layer "B.SilkS")
		)
		(fp_line
			(start 0.7874 -0.4064)
			(end -0.7874 -0.4064)
			(stroke
				(width 0.1524)
				(type default)
			)
			(layer "B.SilkS")
		)
		(fp_line
			(start -0.7874 0.4064)
			(end 0.7874 0.4064)
			(stroke
				(width 0.1524)
				(type default)
			)
			(layer "B.SilkS")
		)
		(fp_line
			(start -0.7874 -0.4064)
			(end -0.7874 0.4064)
			(stroke
				(width 0.1524)
				(type default)
			)
			(layer "B.SilkS")
		)
		(fp_line
			(start 0.67945 0.3048)
			(end 0.67945 -0.305054)
			(stroke
				(width 0.1)
				(type default)
			)
			(layer "B.Fab")
		)
		(fp_line
			(start 0.67945 -0.305054)
			(end 0.12065 -0.305054)
			(stroke
				(width 0.1)
				(type default)
			)
			(layer "B.Fab")
		)
		(fp_line
			(start 0.12065 0.3048)
			(end 0.67945 0.3048)
			(stroke
				(width 0.1)
				(type default)
			)
			(layer "B.Fab")
		)
		(fp_line
			(start 0.12065 0.2794)
			(end 0.12065 0.3048)
			(stroke
				(width 0.1)
				(type default)
			)
			(layer "B.Fab")
		)
		(fp_line
			(start 0.12065 -0.2794)
			(end -0.12065 -0.2794)
			(stroke
				(width 0.1)
				(type default)
			)
			(layer "B.Fab")
		)
		(fp_line
			(start 0.12065 -0.305054)
			(end 0.12065 -0.2794)
			(stroke
				(width 0.1)
				(type default)
			)
			(layer "B.Fab")
		)
		(fp_line
			(start -0.120396 0.3048)
			(end -0.120396 0.2794)
			(stroke
				(width 0.1)
				(type default)
			)
			(layer "B.Fab")
		)
		(fp_line
			(start -0.120396 0.2794)
			(end 0.12065 0.2794)
			(stroke
				(width 0.1)
				(type default)
			)
			(layer "B.Fab")
		)
		(fp_line
			(start -0.12065 -0.2794)
			(end -0.12065 -0.3048)
			(stroke
				(width 0.1)
				(type default)
			)
			(layer "B.Fab")
		)
		(fp_line
			(start -0.12065 -0.3048)
			(end -0.67945 -0.3048)
			(stroke
				(width 0.1)
				(type default)
			)
			(layer "B.Fab")
		)
		(fp_line
			(start -0.67945 0.3048)
			(end -0.120396 0.3048)
			(stroke
				(width 0.1)
				(type default)
			)
			(layer "B.Fab")
		)
		(fp_line
			(start -0.67945 -0.3048)
			(end -0.67945 0.3048)
			(stroke
				(width 0.1)
				(type default)
			)
			(layer "B.Fab")
		)
		(pad "1" smd circle
			(at 0.40005 0)
			(size 0 0)
			(layers "B.Cu" "B.Mask" "B.Paste")
			(net "I3C_SPD_DDRGL_CPU0_SDA")
		)
		(pad "2" smd circle
			(at -0.40005 0)
			(size 0 0)
			(layers "B.Cu" "B.Mask" "B.Paste")
			(net "I3C_SPD_DDRL_CPU0_SDA")
		)
	)
	(footprint ""
		(layer "B.Cu")
		(at 102.214934 -252.234192 60)
		(property "Reference" "C2409"
			(at 0 0 60)
			(layer "B.SilkS")
			(hide yes)
			(effects
				(font
					(size 1.27 1.27)
				)
				(justify mirror)
			)
		)
		(property "Value" ""
			(at 0 0 60)
			(layer "B.Fab")
			(effects
				(font
					(size 1.27 1.27)
				)
				(justify mirror)
			)
		)
		(duplicate_pad_numbers_are_jumpers no)
		(fp_line
			(start -0.787516 -0.406438)
			(end -0.787425 0.40652)
			(stroke
				(width 0.1524)
				(type default)
			)
			(layer "B.SilkS")
		)
		(fp_line
			(start -0.787425 0.40652)
			(end 0.787516 0.406438)
			(stroke
				(width 0.1524)
				(type default)
			)
			(layer "B.SilkS")
		)
		(fp_line
			(start 0.787425 -0.40652)
			(end -0.787516 -0.406438)
			(stroke
				(width 0.1524)
				(type default)
			)
			(layer "B.SilkS")
		)
		(fp_line
			(start 0.787516 0.406438)
			(end 0.787425 -0.40652)
			(stroke
				(width 0.1524)
				(type default)
			)
			(layer "B.SilkS")
		)
		(fp_line
			(start -0.679568 -0.304811)
			(end -0.6795 0.304908)
			(stroke
				(width 0.1)
				(type default)
			)
			(layer "B.Fab")
		)
		(fp_line
			(start -0.120605 -0.304905)
			(end -0.679568 -0.304811)
			(stroke
				(width 0.1)
				(type default)
			)
			(layer "B.Fab")
		)
		(fp_line
			(start -0.120554 -0.279418)
			(end -0.120605 -0.304905)
			(stroke
				(width 0.1)
				(type default)
			)
			(layer "B.Fab")
		)
		(fp_line
			(start 0.120629 -0.30516)
			(end 0.120587 -0.279326)
			(stroke
				(width 0.1)
				(type default)
			)
			(layer "B.Fab")
		)
		(fp_line
			(start 0.120587 -0.279326)
			(end -0.120554 -0.279418)
			(stroke
				(width 0.1)
				(type default)
			)
			(layer "B.Fab")
		)
		(fp_line
			(start -0.6795 0.304908)
			(end -0.120316 0.304686)
			(stroke
				(width 0.1)
				(type default)
			)
			(layer "B.Fab")
		)
		(fp_line
			(start 0.679373 -0.305128)
			(end 0.120629 -0.30516)
			(stroke
				(width 0.1)
				(type default)
			)
			(layer "B.Fab")
		)
		(fp_line
			(start -0.12024 0.279419)
			(end 0.120554 0.279418)
			(stroke
				(width 0.1)
				(type default)
			)
			(layer "B.Fab")
		)
		(fp_line
			(start -0.120316 0.304686)
			(end -0.12024 0.279419)
			(stroke
				(width 0.1)
				(type default)
			)
			(layer "B.Fab")
		)
		(fp_line
			(start 0.120554 0.279418)
			(end 0.120605 0.304905)
			(stroke
				(width 0.1)
				(type default)
			)
			(layer "B.Fab")
		)
		(fp_line
			(start 0.120605 0.304905)
			(end 0.679568 0.304811)
			(stroke
				(width 0.1)
				(type default)
			)
			(layer "B.Fab")
		)
		(fp_line
			(start 0.679568 0.304811)
			(end 0.679373 -0.305128)
			(stroke
				(width 0.1)
				(type default)
			)
			(layer "B.Fab")
		)
		(pad "1" smd circle
			(at 0.40005 0 240)
			(size 0 0)
			(layers "B.Cu" "B.Mask" "B.Paste")
			(net "PVDDCR_SOC_P1")
		)
		(pad "2" smd circle
			(at -0.40005 0 240)
			(size 0 0)
			(layers "B.Cu" "B.Mask" "B.Paste")
			(net "GND")
		)
	)
)
